(kicad_pcb
	(version 20260206)
	(generator "pcbnew")
	(generator_version "10.0")
	(general
		(thickness 1.6)
		(legacy_teardrops no)
	)
	(paper "A4")
	(title_block
		(title "Bryce Canyon_SCC_16316-1_OCP.brd")
		(comment 1 "Bryce Canyon / footprints 483-489 of 1561")
	)
	(layers
		(0 "F.Cu" signal "TOP")
		(4 "In1.Cu" signal "L2GND")
		(6 "In2.Cu" signal "L3")
		(8 "In3.Cu" signal "L4VCC")
		(10 "In4.Cu" signal "L5VCC")
		(12 "In5.Cu" signal "L6")
		(14 "In6.Cu" signal "L7GND")
		(2 "B.Cu" signal "BOTTOM")
		(9 "F.Adhes" user "F.Adhesive")
		(11 "B.Adhes" user "B.Adhesive")
		(13 "F.Paste" user "Package Geometry/Pastemask Top")
		(15 "B.Paste" user "Package Geometry/Pastemask Bottom")
		(5 "F.SilkS" user "Ref Des/Silkscreen Top")
		(7 "B.SilkS" user "Ref Des/Silkscreen Bottom")
		(1 "F.Mask" user "Board Geometry/Soldermask Top")
		(3 "B.Mask" user "Board Geometry/Soldermask Bottom")
		(17 "Dwgs.User" user "User.Drawings")
		(19 "Cmts.User" user "User.Comments")
		(21 "Eco1.User" user "User.Eco1")
		(23 "Eco2.User" user "User.Eco2")
		(25 "Edge.Cuts" user "Board Geometry/Outline")
		(27 "Margin" user)
		(31 "F.CrtYd" user "Package Geometry/Place Bound Top")
		(29 "B.CrtYd" user "Package Geometry/Place Bound Bottom")
		(35 "F.Fab" user "Ref Des/Assembly Top")
		(33 "B.Fab" user "Ref Des/Assembly Bottom")
	)
	(footprint ""
		(layer "F.Cu")
		(at 22.38883 -93.377004 90)
		(property "Reference" "R446"
			(at 0 0 90)
			(layer "F.SilkS")
			(hide yes)
			(effects
				(font
					(size 1.27 1.27)
				)
			)
		)
		(property "Value" "0R2J-2-GP"
			(at 0.064008 -3.993896 90)
			(unlocked yes)
			(layer "F.Fab")
			(hide yes)
			(effects
				(font
					(size 1.016 1.016)
					(thickness 0.1524)
				)
			)
		)
		(property "Device Type" "R402H16"
			(at 0.064008 -5.517896 90)
			(unlocked yes)
			(layer "F.Fab")
			(hide yes)
			(effects
				(font
					(size 1.016 1.016)
					(thickness 0.1524)
				)
			)
		)
		(duplicate_pad_numbers_are_jumpers no)
		(fp_line
			(start 0.508 -0.9398)
			(end -0.508 -0.9398)
			(stroke
				(width 0.1524)
				(type default)
			)
			(layer "F.SilkS")
		)
		(fp_line
			(start -0.508 -0.9398)
			(end -0.508 0.9398)
			(stroke
				(width 0.1524)
				(type default)
			)
			(layer "F.SilkS")
		)
		(fp_rect
			(start -0.508 0.9398)
			(end 0.508 -0.9398)
			(stroke
				(width 0)
				(type default)
			)
			(fill no)
			(layer "F.CrtYd")
		)
		(fp_rect
			(start -0.508 0.9398)
			(end 0.508 -0.9398)
			(stroke
				(width 0)
				(type default)
			)
			(fill no)
			(layer "F.Fab")
		)
		(pad "1" smd custom
			(at 0 -0.4445 90)
			(size 0.1397 0.1397)
			(layers "F.Cu" "F.Mask" "F.Paste")
			(net "LS_EN_U46")
			(options
				(clearance outline)
				(anchor circle)
			)
			(primitives
				(gr_poly
					(pts
						(arc
							(start -0.1778 -0.2794)
							(mid -0.249642 -0.249642)
							(end -0.2794 -0.1778)
						)
						(arc
							(start -0.2794 0.1778)
							(mid -0.249642 0.249642)
							(end -0.1778 0.2794)
						)
						(arc
							(start 0.1778 0.2794)
							(mid 0.249642 0.249642)
							(end 0.2794 0.1778)
						)
						(arc
							(start 0.2794 -0.1778)
							(mid 0.249642 -0.249642)
							(end 0.1778 -0.2794)
						)
					)
					(width 0)
					(fill yes)
				)
			)
		)
		(pad "2" smd custom
			(at 0 0.4445 90)
			(size 0.1397 0.1397)
			(layers "F.Cu" "F.Mask" "F.Paste")
			(net "VREF1")
			(options
				(clearance outline)
				(anchor circle)
			)
			(primitives
				(gr_poly
					(pts
						(arc
							(start -0.1778 -0.2794)
							(mid -0.249642 -0.249642)
							(end -0.2794 -0.1778)
						)
						(arc
							(start -0.2794 0.1778)
							(mid -0.249642 0.249642)
							(end -0.1778 0.2794)
						)
						(arc
							(start 0.1778 0.2794)
							(mid 0.249642 0.249642)
							(end 0.2794 0.1778)
						)
						(arc
							(start 0.2794 -0.1778)
							(mid 0.249642 -0.249642)
							(end 0.1778 -0.2794)
						)
					)
					(width 0)
					(fill yes)
				)
			)
		)
	)
	(footprint ""
		(layer "F.Cu")
		(at 148.190966 -35.15614 102)
		(property "Reference" "C330"
			(at 0 0 102)
			(layer "F.SilkS")
			(hide yes)
			(effects
				(font
					(size 1.27 1.27)
				)
			)
		)
		(property "Value" "SCD01U16V1KX-GP"
			(at -2.832296 -1.73983 102)
			(unlocked yes)
			(layer "F.Fab")
			(hide yes)
			(effects
				(font
					(size 1.016 1.016)
					(thickness 0.1524)
				)
			)
		)
		(property "Device Type" "C0201H13"
			(at -2.832174 -3.263834 102)
			(unlocked yes)
			(layer "F.Fab")
			(hide yes)
			(effects
				(font
					(size 1.016 1.016)
					(thickness 0.1524)
				)
			)
		)
		(duplicate_pad_numbers_are_jumpers no)
		(fp_poly
			(pts
				(xy -0.279454 -0.647706) (xy 0.279346 -0.647706) (xy 0.279346 0.647694) (xy -0.279454 0.647694)
			)
			(stroke
				(width 0)
				(type default)
			)
			(fill no)
			(layer "F.CrtYd")
		)
		(fp_poly
			(pts
				(xy -0.279454 -0.647706) (xy 0.279346 -0.647706) (xy 0.279346 0.647694) (xy -0.279454 0.647694)
			)
			(stroke
				(width 0)
				(type default)
			)
			(fill no)
			(layer "F.Fab")
		)
		(pad "1" smd custom
			(at -0.000001 -0.2794 102)
			(size 0.0762 0.0762)
			(layers "F.Cu" "F.Mask" "F.Paste")
			(net "PHY_SCC_TO_IOC_41_DN")
			(options
				(clearance outline)
				(anchor circle)
			)
			(primitives
				(gr_poly
					(pts
						(arc
							(start 0.1524 -0.127)
							(mid 0.137521 -0.162921)
							(end 0.1016 -0.1778)
						)
						(arc
							(start -0.1016 -0.1778)
							(mid -0.137521 -0.162921)
							(end -0.1524 -0.127)
						)
						(arc
							(start -0.1524 0.127)
							(mid -0.137521 0.162921)
							(end -0.1016 0.1778)
						)
						(arc
							(start 0.1016 0.1778)
							(mid 0.137521 0.162921)
							(end 0.1524 0.127)
						)
					)
					(width 0)
					(fill yes)
				)
			)
		)
		(pad "2" smd custom
			(at 0.000001 0.2794 102)
			(size 0.0762 0.0762)
			(layers "F.Cu" "F.Mask" "F.Paste")
			(net "PHY_SCC_TO_IOC_C_41_DN")
			(options
				(clearance outline)
				(anchor circle)
			)
			(primitives
				(gr_poly
					(pts
						(arc
							(start 0.1524 -0.127)
							(mid 0.137521 -0.162921)
							(end 0.1016 -0.1778)
						)
						(arc
							(start -0.1016 -0.1778)
							(mid -0.137521 -0.162921)
							(end -0.1524 -0.127)
						)
						(arc
							(start -0.1524 0.127)
							(mid -0.137521 0.162921)
							(end -0.1016 0.1778)
						)
						(arc
							(start 0.1016 0.1778)
							(mid 0.137521 0.162921)
							(end 0.1524 0.127)
						)
					)
					(width 0)
					(fill yes)
				)
			)
		)
	)
	(footprint ""
		(layer "F.Cu")
		(at 74.855832 -74.631804)
		(property "Reference" "R529"
			(at 0 0 0)
			(layer "F.SilkS")
			(hide yes)
			(effects
				(font
					(size 1.27 1.27)
				)
			)
		)
		(property "Value" "0R2J-2-GP"
			(at 0.064008 -3.993896 0)
			(unlocked yes)
			(layer "F.Fab")
			(hide yes)
			(effects
				(font
					(size 1.016 1.016)
					(thickness 0.1524)
				)
			)
		)
		(property "Device Type" "R402H16"
			(at 0.064008 -5.517896 0)
			(unlocked yes)
			(layer "F.Fab")
			(hide yes)
			(effects
				(font
					(size 1.016 1.016)
					(thickness 0.1524)
				)
			)
		)
		(duplicate_pad_numbers_are_jumpers no)
		(fp_line
			(start -0.508 -0.9398)
			(end -0.508 0.9398)
			(stroke
				(width 0.1524)
				(type default)
			)
			(layer "F.SilkS")
		)
		(fp_line
			(start 0.508 -0.9398)
			(end -0.508 -0.9398)
			(stroke
				(width 0.1524)
				(type default)
			)
			(layer "F.SilkS")
		)
		(fp_rect
			(start -0.508 0.9398)
			(end 0.508 -0.9398)
			(stroke
				(width 0)
				(type default)
			)
			(fill no)
			(layer "F.CrtYd")
		)
		(fp_rect
			(start -0.508 0.9398)
			(end 0.508 -0.9398)
			(stroke
				(width 0)
				(type default)
			)
			(fill no)
			(layer "F.Fab")
		)
		(pad "1" smd custom
			(at 0 -0.4445)
			(size 0.1397 0.1397)
			(layers "F.Cu" "F.Mask" "F.Paste")
			(net "I2C_EXP_IOC_SCL8")
			(options
				(clearance outline)
				(anchor circle)
			)
			(primitives
				(gr_poly
					(pts
						(arc
							(start -0.1778 -0.2794)
							(mid -0.249642 -0.249642)
							(end -0.2794 -0.1778)
						)
						(arc
							(start -0.2794 0.1778)
							(mid -0.249642 0.249642)
							(end -0.1778 0.2794)
						)
						(arc
							(start 0.1778 0.2794)
							(mid 0.249642 0.249642)
							(end 0.2794 0.1778)
						)
						(arc
							(start 0.2794 -0.1778)
							(mid 0.249642 -0.249642)
							(end 0.1778 -0.2794)
						)
					)
					(width 0)
					(fill yes)
				)
			)
		)
		(pad "2" smd custom
			(at 0 0.4445)
			(size 0.1397 0.1397)
			(layers "F.Cu" "F.Mask" "F.Paste")
			(net "I2C_IOC_4_R_SCL")
			(options
				(clearance outline)
				(anchor circle)
			)
			(primitives
				(gr_poly
					(pts
						(arc
							(start -0.1778 -0.2794)
							(mid -0.249642 -0.249642)
							(end -0.2794 -0.1778)
						)
						(arc
							(start -0.2794 0.1778)
							(mid -0.249642 0.249642)
							(end -0.1778 0.2794)
						)
						(arc
							(start 0.1778 0.2794)
							(mid 0.249642 0.249642)
							(end 0.2794 0.1778)
						)
						(arc
							(start 0.2794 -0.1778)
							(mid 0.249642 -0.249642)
							(end 0.1778 -0.2794)
						)
					)
					(width 0)
					(fill yes)
				)
			)
		)
	)
	(footprint ""
		(layer "F.Cu")
		(at 69.977 -103.505)
		(property "Reference" "C640"
			(at 0 0 0)
			(layer "F.SilkS")
			(hide yes)
			(effects
				(font
					(size 1.27 1.27)
				)
			)
		)
		(property "Value" "SC1KP50V2KX-1GP"
			(at 1.1811 -2.7051 0)
			(unlocked yes)
			(layer "F.Fab")
			(hide yes)
			(effects
				(font
					(size 1.016 1.016)
					(thickness 0.1524)
				)
			)
		)
		(property "Device Type" "C402H22"
			(at 1.1811 -4.2291 0)
			(unlocked yes)
			(layer "F.Fab")
			(hide yes)
			(effects
				(font
					(size 1.016 1.016)
					(thickness 0.1524)
				)
			)
		)
		(duplicate_pad_numbers_are_jumpers no)
		(fp_rect
			(start -0.4318 0.9525)
			(end 0.4318 -0.9525)
			(stroke
				(width 0)
				(type default)
			)
			(fill no)
			(layer "F.CrtYd")
		)
		(fp_rect
			(start -0.4318 0.9525)
			(end 0.4318 -0.9525)
			(stroke
				(width 0)
				(type default)
			)
			(fill no)
			(layer "F.Fab")
		)
		(pad "1" smd custom
			(at 0 -0.4445)
			(size 0.1524 0.1524)
			(layers "F.Cu" "F.Mask" "F.Paste")
			(net "P3V3_LL_R")
			(options
				(clearance outline)
				(anchor circle)
			)
			(primitives
				(gr_poly
					(pts
						(arc
							(start 0.3048 -0.2032)
							(mid 0.275042 -0.275042)
							(end 0.2032 -0.3048)
						)
						(arc
							(start -0.2032 -0.3048)
							(mid -0.275042 -0.275042)
							(end -0.3048 -0.2032)
						)
						(arc
							(start -0.3048 0.2032)
							(mid -0.275042 0.275042)
							(end -0.2032 0.3048)
						)
						(arc
							(start 0.2032 0.3048)
							(mid 0.275042 0.275042)
							(end 0.3048 0.2032)
						)
					)
					(width 0)
					(fill yes)
				)
			)
		)
		(pad "2" smd custom
			(at 0 0.4445)
			(size 0.1524 0.1524)
			(layers "F.Cu" "F.Mask" "F.Paste")
			(net "P3V3_VFB")
			(options
				(clearance outline)
				(anchor circle)
			)
			(primitives
				(gr_poly
					(pts
						(arc
							(start 0.3048 -0.2032)
							(mid 0.275042 -0.275042)
							(end 0.2032 -0.3048)
						)
						(arc
							(start -0.2032 -0.3048)
							(mid -0.275042 -0.275042)
							(end -0.3048 -0.2032)
						)
						(arc
							(start -0.3048 0.2032)
							(mid -0.275042 0.275042)
							(end -0.2032 0.3048)
						)
						(arc
							(start 0.2032 0.3048)
							(mid 0.275042 0.275042)
							(end 0.3048 0.2032)
						)
					)
					(width 0)
					(fill yes)
				)
			)
		)
	)
	(footprint ""
		(layer "F.Cu")
		(at 61.849 -24.13 90)
		(property "Reference" "C734"
			(at 0 0 90)
			(layer "F.SilkS")
			(hide yes)
			(effects
				(font
					(size 1.27 1.27)
				)
			)
		)
		(property "Value" "SCD1U16V2KX-3GP"
			(at 1.1811 -2.7051 90)
			(unlocked yes)
			(layer "F.Fab")
			(hide yes)
			(effects
				(font
					(size 1.016 1.016)
					(thickness 0.1524)
				)
			)
		)
		(property "Device Type" "C402H22"
			(at 1.1811 -4.2291 90)
			(unlocked yes)
			(layer "F.Fab")
			(hide yes)
			(effects
				(font
					(size 1.016 1.016)
					(thickness 0.1524)
				)
			)
		)
		(duplicate_pad_numbers_are_jumpers no)
		(fp_rect
			(start -0.4318 0.9525)
			(end 0.4318 -0.9525)
			(stroke
				(width 0)
				(type default)
			)
			(fill no)
			(layer "F.CrtYd")
		)
		(fp_rect
			(start -0.4318 0.9525)
			(end 0.4318 -0.9525)
			(stroke
				(width 0)
				(type default)
			)
			(fill no)
			(layer "F.Fab")
		)
		(pad "1" smd custom
			(at 0 -0.4445 90)
			(size 0.1524 0.1524)
			(layers "F.Cu" "F.Mask" "F.Paste")
			(net "P3V3")
			(options
				(clearance outline)
				(anchor circle)
			)
			(primitives
				(gr_poly
					(pts
						(arc
							(start 0.3048 -0.2032)
							(mid 0.275042 -0.275042)
							(end 0.2032 -0.3048)
						)
						(arc
							(start -0.2032 -0.3048)
							(mid -0.275042 -0.275042)
							(end -0.3048 -0.2032)
						)
						(arc
							(start -0.3048 0.2032)
							(mid -0.275042 0.275042)
							(end -0.2032 0.3048)
						)
						(arc
							(start 0.2032 0.3048)
							(mid 0.275042 0.275042)
							(end 0.3048 0.2032)
						)
					)
					(width 0)
					(fill yes)
				)
			)
		)
		(pad "2" smd custom
			(at 0 0.4445 90)
			(size 0.1524 0.1524)
			(layers "F.Cu" "F.Mask" "F.Paste")
			(net "GND")
			(options
				(clearance outline)
				(anchor circle)
			)
			(primitives
				(gr_poly
					(pts
						(arc
							(start 0.3048 -0.2032)
							(mid 0.275042 -0.275042)
							(end 0.2032 -0.3048)
						)
						(arc
							(start -0.2032 -0.3048)
							(mid -0.275042 -0.275042)
							(end -0.3048 -0.2032)
						)
						(arc
							(start -0.3048 0.2032)
							(mid -0.275042 0.275042)
							(end -0.2032 0.3048)
						)
						(arc
							(start 0.2032 0.3048)
							(mid 0.275042 0.275042)
							(end 0.3048 0.2032)
						)
					)
					(width 0)
					(fill yes)
				)
			)
		)
	)
	(footprint ""
		(layer "F.Cu")
		(at 187.0456 -116.6876 180)
		(property "Reference" "C691"
			(at 0 0 180)
			(layer "F.SilkS")
			(hide yes)
			(effects
				(font
					(size 1.27 1.27)
				)
			)
		)
		(property "Value" "SCD47U25V3KX-3-GP"
			(at 0 -2.8194 180)
			(unlocked yes)
			(layer "F.Fab")
			(hide yes)
			(effects
				(font
					(size 1.016 1.016)
					(thickness 0.1524)
				)
			)
		)
		(property "Device Type" "C603H36"
			(at 0 -4.3434 180)
			(unlocked yes)
			(layer "F.Fab")
			(hide yes)
			(effects
				(font
					(size 1.016 1.016)
					(thickness 0.1524)
				)
			)
		)
		(duplicate_pad_numbers_are_jumpers no)
		(fp_line
			(start 0.508 0)
			(end -0.508 0)
			(stroke
				(width 0.2032)
				(type default)
			)
			(layer "F.SilkS")
		)
		(fp_rect
			(start -0.5842 1.3335)
			(end 0.5842 -1.3335)
			(stroke
				(width 0)
				(type default)
			)
			(fill no)
			(layer "F.CrtYd")
		)
		(fp_rect
			(start -0.5842 1.3335)
			(end 0.5842 -1.3335)
			(stroke
				(width 0)
				(type default)
			)
			(fill no)
			(layer "F.Fab")
		)
		(pad "1" smd custom
			(at 0 -0.762 180)
			(size 0.2159 0.2159)
			(layers "F.Cu" "F.Mask" "F.Paste")
			(net "P1V8_C_G_PG")
			(options
				(clearance outline)
				(anchor circle)
			)
			(primitives
				(gr_poly
					(pts
						(arc
							(start -0.3302 -0.4318)
							(mid -0.402042 -0.402042)
							(end -0.4318 -0.3302)
						)
						(arc
							(start -0.4318 0.3302)
							(mid -0.402042 0.402042)
							(end -0.3302 0.4318)
						)
						(arc
							(start 0.3302 0.4318)
							(mid 0.402042 0.402042)
							(end 0.4318 0.3302)
						)
						(arc
							(start 0.4318 -0.3302)
							(mid 0.402042 -0.402042)
							(end 0.3302 -0.4318)
						)
					)
					(width 0)
					(fill yes)
				)
			)
		)
		(pad "2" smd custom
			(at 0 0.762 180)
			(size 0.2159 0.2159)
			(layers "F.Cu" "F.Mask" "F.Paste")
			(net "P1V8_C")
			(options
				(clearance outline)
				(anchor circle)
			)
			(primitives
				(gr_poly
					(pts
						(arc
							(start -0.3302 -0.4318)
							(mid -0.402042 -0.402042)
							(end -0.4318 -0.3302)
						)
						(arc
							(start -0.4318 0.3302)
							(mid -0.402042 0.402042)
							(end -0.3302 0.4318)
						)
						(arc
							(start 0.3302 0.4318)
							(mid 0.402042 0.402042)
							(end 0.4318 0.3302)
						)
						(arc
							(start 0.4318 -0.3302)
							(mid 0.402042 -0.402042)
							(end 0.3302 -0.4318)
						)
					)
					(width 0)
					(fill yes)
				)
			)
		)
	)
	(footprint ""
		(layer "F.Cu")
		(at 128.58623 -44.732448 180)
		(property "Reference" "C46"
			(at 0 0 180)
			(layer "F.SilkS")
			(hide yes)
			(effects
				(font
					(size 1.27 1.27)
				)
			)
		)
		(property "Value" "SCD01U16V1KX-GP"
			(at -2.8321 -1.7399 180)
			(unlocked yes)
			(layer "F.Fab")
			(hide yes)
			(effects
				(font
					(size 1.016 1.016)
					(thickness 0.1524)
				)
			)
		)
		(property "Device Type" "C0201H13"
			(at -2.8321 -3.2639 180)
			(unlocked yes)
			(layer "F.Fab")
			(hide yes)
			(effects
				(font
					(size 1.016 1.016)
					(thickness 0.1524)
				)
			)
		)
		(duplicate_pad_numbers_are_jumpers no)
		(fp_rect
			(start -0.2794 0.6477)
			(end 0.2794 -0.6477)
			(stroke
				(width 0)
				(type default)
			)
			(fill no)
			(layer "F.CrtYd")
		)
		(fp_rect
			(start -0.2794 0.6477)
			(end 0.2794 -0.6477)
			(stroke
				(width 0)
				(type default)
			)
			(fill no)
			(layer "F.Fab")
		)
		(pad "1" smd custom
			(at 0 -0.2794 180)
			(size 0.0762 0.0762)
			(layers "F.Cu" "F.Mask" "F.Paste")
			(net "PHY_IOC_TO_SCC_41_DN")
			(options
				(clearance outline)
				(anchor circle)
			)
			(primitives
				(gr_poly
					(pts
						(arc
							(start 0.1524 -0.127)
							(mid 0.137521 -0.162921)
							(end 0.1016 -0.1778)
						)
						(arc
							(start -0.1016 -0.1778)
							(mid -0.137521 -0.162921)
							(end -0.1524 -0.127)
						)
						(arc
							(start -0.1524 0.127)
							(mid -0.137521 0.162921)
							(end -0.1016 0.1778)
						)
						(arc
							(start 0.1016 0.1778)
							(mid 0.137521 0.162921)
							(end 0.1524 0.127)
						)
					)
					(width 0)
					(fill yes)
				)
			)
		)
		(pad "2" smd custom
			(at 0 0.2794 180)
			(size 0.0762 0.0762)
			(layers "F.Cu" "F.Mask" "F.Paste")
			(net "PHY_IOC_TO_SCC_C_41_DN")
			(options
				(clearance outline)
				(anchor circle)
			)
			(primitives
				(gr_poly
					(pts
						(arc
							(start 0.1524 -0.127)
							(mid 0.137521 -0.162921)
							(end 0.1016 -0.1778)
						)
						(arc
							(start -0.1016 -0.1778)
							(mid -0.137521 -0.162921)
							(end -0.1524 -0.127)
						)
						(arc
							(start -0.1524 0.127)
							(mid -0.137521 0.162921)
							(end -0.1016 0.1778)
						)
						(arc
							(start 0.1016 0.1778)
							(mid 0.137521 0.162921)
							(end 0.1524 0.127)
						)
					)
					(width 0)
					(fill yes)
				)
			)
		)
	)
)
